(kicad_pcb
	(version 20260206)
	(generator "pcbnew")
	(generator_version "10.0")
	(general
		(thickness 1.6)
		(legacy_teardrops no)
	)
	(paper "A4")
	(title_block
		(title "baseboard — 13948-1b.1110WZS1818.brd")
		(comment 1 "Honey Badger (Wiwynn) / footprints 2196-2204 of 2523")
	)
	(layers
		(0 "F.Cu" signal "TOP")
		(4 "In1.Cu" signal "L2GND")
		(6 "In2.Cu" signal "L3")
		(8 "In3.Cu" signal "L4VCC")
		(10 "In4.Cu" signal "L5VCC")
		(12 "In5.Cu" signal "L6")
		(14 "In6.Cu" signal "L7GND")
		(2 "B.Cu" signal "BOTTOM")
		(9 "F.Adhes" user "F.Adhesive")
		(11 "B.Adhes" user "B.Adhesive")
		(13 "F.Paste" user "Package Geometry/Pastemask Top")
		(15 "B.Paste" user "Package Geometry/Pastemask Bottom")
		(5 "F.SilkS" user "Ref Des/Silkscreen Top")
		(7 "B.SilkS" user "Ref Des/Silkscreen Bottom")
		(1 "F.Mask" user "Board Geometry/Soldermask Top")
		(3 "B.Mask" user "Board Geometry/Soldermask Bottom")
		(17 "Dwgs.User" user "User.Drawings")
		(19 "Cmts.User" user "User.Comments")
		(21 "Eco1.User" user "User.Eco1")
		(23 "Eco2.User" user "User.Eco2")
		(25 "Edge.Cuts" user "Board Geometry/Outline")
		(27 "Margin" user)
		(31 "F.CrtYd" user "Package Geometry/Place Bound Top")
		(29 "B.CrtYd" user "Package Geometry/Place Bound Bottom")
		(35 "F.Fab" user "Ref Des/Assembly Top")
		(33 "B.Fab" user "Ref Des/Assembly Bottom")
	)
	(footprint ""
		(layer "B.Cu")
		(at 110.83417 -99.8474)
		(property "Reference" "SC1135"
			(at 0 0 0)
			(layer "B.SilkS")
			(hide yes)
			(effects
				(font
					(size 1.27 1.27)
				)
				(justify mirror)
			)
		)
		(property "Value" "SCD1U6D3V1KX-GP"
			(at 2.8321 -1.7399 0)
			(unlocked yes)
			(layer "B.Fab")
			(hide yes)
			(effects
				(font
					(size 1.016 1.016)
					(thickness 0.1524)
				)
				(justify mirror)
			)
		)
		(property "Device Type" "C0201H13"
			(at 2.8321 -3.2639 0)
			(unlocked yes)
			(layer "B.Fab")
			(hide yes)
			(effects
				(font
					(size 1.016 1.016)
					(thickness 0.1524)
				)
				(justify mirror)
			)
		)
		(duplicate_pad_numbers_are_jumpers no)
		(fp_rect
			(start 0.2794 0.6477)
			(end -0.2794 -0.6477)
			(stroke
				(width 0)
				(type default)
			)
			(fill no)
			(layer "B.CrtYd")
		)
		(fp_rect
			(start 0.2794 0.6477)
			(end -0.2794 -0.6477)
			(stroke
				(width 0)
				(type default)
			)
			(fill no)
			(layer "B.Fab")
		)
		(pad "1" smd custom
			(at 0 -0.2794 180)
			(size 0.0762 0.0762)
			(layers "B.Cu" "B.Mask" "B.Paste")
			(net "GB_VDDH2")
			(options
				(clearance outline)
				(anchor circle)
			)
			(primitives
				(gr_poly
					(pts
						(arc
							(start 0.1524 0.127)
							(mid 0.137521 0.162921)
							(end 0.1016 0.1778)
						)
						(arc
							(start -0.1016 0.1778)
							(mid -0.137521 0.162921)
							(end -0.1524 0.127)
						)
						(arc
							(start -0.1524 -0.127)
							(mid -0.137521 -0.162921)
							(end -0.1016 -0.1778)
						)
						(arc
							(start 0.1016 -0.1778)
							(mid 0.137521 -0.162921)
							(end 0.1524 -0.127)
						)
					)
					(width 0)
					(fill yes)
				)
			)
		)
		(pad "2" smd custom
			(at 0 0.2794 180)
			(size 0.0762 0.0762)
			(layers "B.Cu" "B.Mask" "B.Paste")
			(net "GND")
			(options
				(clearance outline)
				(anchor circle)
			)
			(primitives
				(gr_poly
					(pts
						(arc
							(start 0.1524 0.127)
							(mid 0.137521 0.162921)
							(end 0.1016 0.1778)
						)
						(arc
							(start -0.1016 0.1778)
							(mid -0.137521 0.162921)
							(end -0.1524 0.127)
						)
						(arc
							(start -0.1524 -0.127)
							(mid -0.137521 -0.162921)
							(end -0.1016 -0.1778)
						)
						(arc
							(start 0.1016 -0.1778)
							(mid 0.137521 -0.162921)
							(end 0.1524 -0.127)
						)
					)
					(width 0)
					(fill yes)
				)
			)
		)
	)
	(footprint ""
		(layer "B.Cu")
		(at 119.01297 -82.042)
		(property "Reference" "STP111"
			(at 0 0 0)
			(layer "B.SilkS")
			(hide yes)
			(effects
				(font
					(size 1.27 1.27)
				)
				(justify mirror)
			)
		)
		(property "Value" "TPAD28"
			(at -0.0127 -1.8034 0)
			(unlocked yes)
			(layer "B.Fab")
			(hide yes)
			(effects
				(font
					(size 1.016 1.016)
					(thickness 0.1524)
				)
				(justify mirror)
			)
		)
		(property "Device Type" "TPAD28"
			(at -0.0127 -3.3274 0)
			(unlocked yes)
			(layer "B.Fab")
			(hide yes)
			(effects
				(font
					(size 1.016 1.016)
					(thickness 0.1524)
				)
				(justify mirror)
			)
		)
		(duplicate_pad_numbers_are_jumpers no)
		(fp_poly
			(pts
				(arc
					(start 0.3556 0)
					(mid -0.3556 0)
					(end 0.3556 0)
				)
			)
			(stroke
				(width 0)
				(type default)
			)
			(fill no)
			(layer "B.CrtYd")
		)
		(fp_poly
			(pts
				(arc
					(start 0.6096 0)
					(mid -0.6096 0)
					(end 0.6096 0)
				)
			)
			(stroke
				(width 0)
				(type default)
			)
			(fill no)
			(layer "B.Fab")
		)
		(pad "1" smd circle
			(at 0 0 180)
			(size 0.7112 0.7112)
			(layers "B.Cu" "B.Mask" "B.Paste")
			(net "TEST_MUX_44")
		)
	)
	(footprint ""
		(layer "B.Cu")
		(at 274.193 -176.657 90)
		(property "Reference" "R344"
			(at 0 0 90)
			(layer "B.SilkS")
			(hide yes)
			(effects
				(font
					(size 1.27 1.27)
				)
				(justify mirror)
			)
		)
		(property "Value" "3K3R2F-2-GP"
			(at -0.064008 -3.993896 90)
			(unlocked yes)
			(layer "B.Fab")
			(hide yes)
			(effects
				(font
					(size 1.016 1.016)
					(thickness 0.1524)
				)
				(justify mirror)
			)
		)
		(property "Device Type" "R402H16"
			(at -0.064008 -5.517896 90)
			(unlocked yes)
			(layer "B.Fab")
			(hide yes)
			(effects
				(font
					(size 1.016 1.016)
					(thickness 0.1524)
				)
				(justify mirror)
			)
		)
		(duplicate_pad_numbers_are_jumpers no)
		(fp_line
			(start 0.508 -0.9398)
			(end 0.508 0.9398)
			(stroke
				(width 0.1524)
				(type default)
			)
			(layer "B.SilkS")
		)
		(fp_line
			(start -0.508 -0.9398)
			(end 0.508 -0.9398)
			(stroke
				(width 0.1524)
				(type default)
			)
			(layer "B.SilkS")
		)
		(fp_rect
			(start 0.508 0.9398)
			(end -0.508 -0.9398)
			(stroke
				(width 0)
				(type default)
			)
			(fill no)
			(layer "B.CrtYd")
		)
		(fp_rect
			(start 0.508 0.9398)
			(end -0.508 -0.9398)
			(stroke
				(width 0)
				(type default)
			)
			(fill no)
			(layer "B.Fab")
		)
		(pad "1" smd custom
			(at 0 -0.4445 270)
			(size 0.1397 0.1397)
			(layers "B.Cu" "B.Mask" "B.Paste")
			(net "P3V3_STBY")
			(options
				(clearance outline)
				(anchor circle)
			)
			(primitives
				(gr_poly
					(pts
						(arc
							(start -0.1778 0.2794)
							(mid -0.249642 0.249642)
							(end -0.2794 0.1778)
						)
						(arc
							(start -0.2794 -0.1778)
							(mid -0.249642 -0.249642)
							(end -0.1778 -0.2794)
						)
						(arc
							(start 0.1778 -0.2794)
							(mid 0.249642 -0.249642)
							(end 0.2794 -0.1778)
						)
						(arc
							(start 0.2794 0.1778)
							(mid 0.249642 0.249642)
							(end 0.1778 0.2794)
						)
					)
					(width 0)
					(fill yes)
				)
			)
		)
		(pad "2" smd custom
			(at 0 0.4445 270)
			(size 0.1397 0.1397)
			(layers "B.Cu" "B.Mask" "B.Paste")
			(net "ROMA9")
			(options
				(clearance outline)
				(anchor circle)
			)
			(primitives
				(gr_poly
					(pts
						(arc
							(start -0.1778 0.2794)
							(mid -0.249642 0.249642)
							(end -0.2794 0.1778)
						)
						(arc
							(start -0.2794 -0.1778)
							(mid -0.249642 -0.249642)
							(end -0.1778 -0.2794)
						)
						(arc
							(start 0.1778 -0.2794)
							(mid 0.249642 -0.249642)
							(end 0.2794 -0.1778)
						)
						(arc
							(start 0.2794 0.1778)
							(mid 0.249642 0.249642)
							(end 0.1778 0.2794)
						)
					)
					(width 0)
					(fill yes)
				)
			)
		)
	)
	(footprint ""
		(layer "B.Cu")
		(at 256.159 -16.891 -90)
		(property "Reference" "R408"
			(at 0 0 90)
			(layer "B.SilkS")
			(hide yes)
			(effects
				(font
					(size 1.27 1.27)
				)
				(justify mirror)
			)
		)
		(property "Value" "15KR2F-GP"
			(at -0.064008 -3.993896 270)
			(unlocked yes)
			(layer "B.Fab")
			(hide yes)
			(effects
				(font
					(size 1.016 1.016)
					(thickness 0.1524)
				)
				(justify mirror)
			)
		)
		(property "Device Type" "R402H16"
			(at -0.064008 -5.517896 270)
			(unlocked yes)
			(layer "B.Fab")
			(hide yes)
			(effects
				(font
					(size 1.016 1.016)
					(thickness 0.1524)
				)
				(justify mirror)
			)
		)
		(duplicate_pad_numbers_are_jumpers no)
		(fp_line
			(start -0.508 -0.9398)
			(end 0.508 -0.9398)
			(stroke
				(width 0.1524)
				(type default)
			)
			(layer "B.SilkS")
		)
		(fp_line
			(start 0.508 -0.9398)
			(end 0.508 0.9398)
			(stroke
				(width 0.1524)
				(type default)
			)
			(layer "B.SilkS")
		)
		(fp_rect
			(start 0.508 0.9398)
			(end -0.508 -0.9398)
			(stroke
				(width 0)
				(type default)
			)
			(fill no)
			(layer "B.CrtYd")
		)
		(fp_rect
			(start 0.508 0.9398)
			(end -0.508 -0.9398)
			(stroke
				(width 0)
				(type default)
			)
			(fill no)
			(layer "B.Fab")
		)
		(pad "1" smd custom
			(at 0 -0.4445 90)
			(size 0.1397 0.1397)
			(layers "B.Cu" "B.Mask" "B.Paste")
			(net "USB_OCS_N1")
			(options
				(clearance outline)
				(anchor circle)
			)
			(primitives
				(gr_poly
					(pts
						(arc
							(start -0.1778 0.2794)
							(mid -0.249642 0.249642)
							(end -0.2794 0.1778)
						)
						(arc
							(start -0.2794 -0.1778)
							(mid -0.249642 -0.249642)
							(end -0.1778 -0.2794)
						)
						(arc
							(start 0.1778 -0.2794)
							(mid 0.249642 -0.249642)
							(end 0.2794 -0.1778)
						)
						(arc
							(start 0.2794 0.1778)
							(mid 0.249642 0.249642)
							(end 0.1778 0.2794)
						)
					)
					(width 0)
					(fill yes)
				)
			)
		)
		(pad "2" smd custom
			(at 0 0.4445 90)
			(size 0.1397 0.1397)
			(layers "B.Cu" "B.Mask" "B.Paste")
			(net "GND")
			(options
				(clearance outline)
				(anchor circle)
			)
			(primitives
				(gr_poly
					(pts
						(arc
							(start -0.1778 0.2794)
							(mid -0.249642 0.249642)
							(end -0.2794 0.1778)
						)
						(arc
							(start -0.2794 -0.1778)
							(mid -0.249642 -0.249642)
							(end -0.1778 -0.2794)
						)
						(arc
							(start 0.1778 -0.2794)
							(mid 0.249642 -0.249642)
							(end 0.2794 -0.1778)
						)
						(arc
							(start 0.2794 0.1778)
							(mid 0.249642 0.249642)
							(end 0.1778 0.2794)
						)
					)
					(width 0)
					(fill yes)
				)
			)
		)
	)
	(footprint ""
		(layer "B.Cu")
		(at 129.648966 -35.814 90)
		(property "Reference" "SL6"
			(at 0 0 90)
			(layer "B.SilkS")
			(hide yes)
			(effects
				(font
					(size 1.27 1.27)
				)
				(justify mirror)
			)
		)
		(property "Value" "MPZ2012S601AT-GP"
			(at 0 -4.2418 90)
			(unlocked yes)
			(layer "B.Fab")
			(hide yes)
			(effects
				(font
					(size 1.016 1.016)
					(thickness 0.1524)
				)
				(justify mirror)
			)
		)
		(property "Device Type" "L805H42"
			(at 0 -5.7912 90)
			(unlocked yes)
			(layer "B.Fab")
			(hide yes)
			(effects
				(font
					(size 1.016 1.016)
					(thickness 0.1524)
				)
				(justify mirror)
			)
		)
		(duplicate_pad_numbers_are_jumpers no)
		(fp_line
			(start 0.889 -1.7018)
			(end -0.889 -1.7018)
			(stroke
				(width 0.1524)
				(type default)
			)
			(layer "B.SilkS")
		)
		(fp_line
			(start -0.889 -1.7018)
			(end -0.889 1.7018)
			(stroke
				(width 0.1524)
				(type default)
			)
			(layer "B.SilkS")
		)
		(fp_line
			(start 0.889 1.7018)
			(end 0.889 -1.7018)
			(stroke
				(width 0.1524)
				(type default)
			)
			(layer "B.SilkS")
		)
		(fp_line
			(start -0.889 1.7018)
			(end 0.889 1.7018)
			(stroke
				(width 0.1524)
				(type default)
			)
			(layer "B.SilkS")
		)
		(fp_rect
			(start 0.9652 1.778)
			(end -0.9652 -1.778)
			(stroke
				(width 0)
				(type default)
			)
			(fill no)
			(layer "B.CrtYd")
		)
		(fp_rect
			(start 0.9652 1.778)
			(end -0.9652 -1.778)
			(stroke
				(width 0)
				(type default)
			)
			(fill no)
			(layer "B.Fab")
		)
		(pad "1" smd rect
			(at 0 -0.9652 270)
			(size 1.397 1.143)
			(layers "B.Cu" "B.Mask" "B.Paste")
			(net "PLL_VDD")
		)
		(pad "2" smd rect
			(at 0 0.9652 270)
			(size 1.397 1.143)
			(layers "B.Cu" "B.Mask" "B.Paste")
			(net "P1V8_C")
		)
	)
	(footprint ""
		(layer "B.Cu")
		(at 113.773966 -28.829 -90)
		(property "Reference" "SR654"
			(at 0 0 90)
			(layer "B.SilkS")
			(hide yes)
			(effects
				(font
					(size 1.27 1.27)
				)
				(justify mirror)
			)
		)
		(property "Value" "4K7R2F-GP"
			(at -0.064008 -3.993896 270)
			(unlocked yes)
			(layer "B.Fab")
			(hide yes)
			(effects
				(font
					(size 1.016 1.016)
					(thickness 0.1524)
				)
				(justify mirror)
			)
		)
		(property "Device Type" "R402H16"
			(at -0.064008 -5.517896 270)
			(unlocked yes)
			(layer "B.Fab")
			(hide yes)
			(effects
				(font
					(size 1.016 1.016)
					(thickness 0.1524)
				)
				(justify mirror)
			)
		)
		(duplicate_pad_numbers_are_jumpers no)
		(fp_line
			(start -0.508 -0.9398)
			(end 0.508 -0.9398)
			(stroke
				(width 0.1524)
				(type default)
			)
			(layer "B.SilkS")
		)
		(fp_line
			(start 0.508 -0.9398)
			(end 0.508 0.9398)
			(stroke
				(width 0.1524)
				(type default)
			)
			(layer "B.SilkS")
		)
		(fp_rect
			(start 0.508 0.9398)
			(end -0.508 -0.9398)
			(stroke
				(width 0)
				(type default)
			)
			(fill no)
			(layer "B.CrtYd")
		)
		(fp_rect
			(start 0.508 0.9398)
			(end -0.508 -0.9398)
			(stroke
				(width 0)
				(type default)
			)
			(fill no)
			(layer "B.Fab")
		)
		(pad "1" smd custom
			(at 0 -0.4445 90)
			(size 0.1397 0.1397)
			(layers "B.Cu" "B.Mask" "B.Paste")
			(net "P1V8_C")
			(options
				(clearance outline)
				(anchor circle)
			)
			(primitives
				(gr_poly
					(pts
						(arc
							(start -0.1778 0.2794)
							(mid -0.249642 0.249642)
							(end -0.2794 0.1778)
						)
						(arc
							(start -0.2794 -0.1778)
							(mid -0.249642 -0.249642)
							(end -0.1778 -0.2794)
						)
						(arc
							(start 0.1778 -0.2794)
							(mid 0.249642 -0.249642)
							(end 0.2794 -0.1778)
						)
						(arc
							(start 0.2794 0.1778)
							(mid 0.249642 0.249642)
							(end 0.1778 0.2794)
						)
					)
					(width 0)
					(fill yes)
				)
			)
		)
		(pad "2" smd custom
			(at 0 0.4445 90)
			(size 0.1397 0.1397)
			(layers "B.Cu" "B.Mask" "B.Paste")
			(net "SYS_RST")
			(options
				(clearance outline)
				(anchor circle)
			)
			(primitives
				(gr_poly
					(pts
						(arc
							(start -0.1778 0.2794)
							(mid -0.249642 0.249642)
							(end -0.2794 0.1778)
						)
						(arc
							(start -0.2794 -0.1778)
							(mid -0.249642 -0.249642)
							(end -0.1778 -0.2794)
						)
						(arc
							(start 0.1778 -0.2794)
							(mid 0.249642 -0.249642)
							(end 0.2794 -0.1778)
						)
						(arc
							(start 0.2794 0.1778)
							(mid 0.249642 0.249642)
							(end 0.1778 0.2794)
						)
					)
					(width 0)
					(fill yes)
				)
			)
		)
	)
	(footprint ""
		(layer "B.Cu")
		(at 102.37597 -82.55)
		(property "Reference" "SC1232"
			(at 0 0 0)
			(layer "B.SilkS")
			(hide yes)
			(effects
				(font
					(size 1.27 1.27)
				)
				(justify mirror)
			)
		)
		(property "Value" "SCD1U6D3V1KX-GP"
			(at 2.8321 -1.7399 0)
			(unlocked yes)
			(layer "B.Fab")
			(hide yes)
			(effects
				(font
					(size 1.016 1.016)
					(thickness 0.1524)
				)
				(justify mirror)
			)
		)
		(property "Device Type" "C0201H13"
			(at 2.8321 -3.2639 0)
			(unlocked yes)
			(layer "B.Fab")
			(hide yes)
			(effects
				(font
					(size 1.016 1.016)
					(thickness 0.1524)
				)
				(justify mirror)
			)
		)
		(duplicate_pad_numbers_are_jumpers no)
		(fp_rect
			(start 0.2794 0.6477)
			(end -0.2794 -0.6477)
			(stroke
				(width 0)
				(type default)
			)
			(fill no)
			(layer "B.CrtYd")
		)
		(fp_rect
			(start 0.2794 0.6477)
			(end -0.2794 -0.6477)
			(stroke
				(width 0)
				(type default)
			)
			(fill no)
			(layer "B.Fab")
		)
		(pad "1" smd custom
			(at 0 -0.2794 180)
			(size 0.0762 0.0762)
			(layers "B.Cu" "B.Mask" "B.Paste")
			(net "P1V8_E")
			(options
				(clearance outline)
				(anchor circle)
			)
			(primitives
				(gr_poly
					(pts
						(arc
							(start 0.1524 0.127)
							(mid 0.137521 0.162921)
							(end 0.1016 0.1778)
						)
						(arc
							(start -0.1016 0.1778)
							(mid -0.137521 0.162921)
							(end -0.1524 0.127)
						)
						(arc
							(start -0.1524 -0.127)
							(mid -0.137521 -0.162921)
							(end -0.1016 -0.1778)
						)
						(arc
							(start 0.1016 -0.1778)
							(mid 0.137521 -0.162921)
							(end 0.1524 -0.127)
						)
					)
					(width 0)
					(fill yes)
				)
			)
		)
		(pad "2" smd custom
			(at 0 0.2794 180)
			(size 0.0762 0.0762)
			(layers "B.Cu" "B.Mask" "B.Paste")
			(net "GND")
			(options
				(clearance outline)
				(anchor circle)
			)
			(primitives
				(gr_poly
					(pts
						(arc
							(start 0.1524 0.127)
							(mid 0.137521 0.162921)
							(end 0.1016 0.1778)
						)
						(arc
							(start -0.1016 0.1778)
							(mid -0.137521 0.162921)
							(end -0.1524 0.127)
						)
						(arc
							(start -0.1524 -0.127)
							(mid -0.137521 -0.162921)
							(end -0.1016 -0.1778)
						)
						(arc
							(start 0.1016 -0.1778)
							(mid 0.137521 -0.162921)
							(end 0.1524 -0.127)
						)
					)
					(width 0)
					(fill yes)
				)
			)
		)
	)
	(footprint ""
		(layer "B.Cu")
		(at 331.499718 -66.73723)
		(property "Reference" ""
			(at 0 0 0)
			(layer "B.SilkS")
			(hide yes)
			(effects
				(font
					(size 1.27 1.27)
				)
				(justify mirror)
			)
		)
		(property "Value" "*"
			(at 5.5753 -0.4572 0)
			(unlocked yes)
			(layer "B.Fab")
			(hide yes)
			(effects
				(font
					(size 1.016 1.016)
					(thickness 0.1524)
				)
				(justify mirror)
			)
		)
		(duplicate_pad_numbers_are_jumpers no)
		(fp_poly
			(pts
				(arc
					(start 4.3053 0)
					(mid -4.3053 0)
					(end 4.3053 0)
				)
			)
			(stroke
				(width 0)
				(type default)
			)
			(fill no)
			(layer "B.CrtYd")
		)
		(fp_poly
			(pts
				(arc
					(start 4.3053 0)
					(mid -4.3053 0)
					(end 4.3053 0)
				)
			)
			(stroke
				(width 0)
				(type default)
			)
			(fill no)
			(layer "B.Fab")
		)
		(pad "1" smd custom
			(at 2.95275 0 180)
			(size 2.000013 2.000013)
			(layers "B.Cu" "B.Mask" "B.Paste")
			(net "Net_54")
			(options
				(clearance outline)
				(anchor circle)
			)
			(primitives
				(gr_poly
					(pts
						(arc
							(start 4.0005 -0.00254)
							(mid -4.000501 0)
							(end 4.0005 0.00254)
						)
						(arc
							(start 1.905 0.00254)
							(mid -1.905002 0)
							(end 1.905 -0.00254)
						)
					)
					(width 0)
					(fill yes)
				)
			)
		)
	)
	(footprint ""
		(layer "B.Cu")
		(at 296.790872 -175.078136 -90)
		(property "Reference" "C206"
			(at 0 0 90)
			(layer "B.SilkS")
			(hide yes)
			(effects
				(font
					(size 1.27 1.27)
				)
				(justify mirror)
			)
		)
		(property "Value" "SC1U10V2KX-1GP"
			(at -1.1811 -2.7051 270)
			(unlocked yes)
			(layer "B.Fab")
			(hide yes)
			(effects
				(font
					(size 1.016 1.016)
					(thickness 0.1524)
				)
				(justify mirror)
			)
		)
		(property "Device Type" "C402H22"
			(at -1.1811 -4.2291 270)
			(unlocked yes)
			(layer "B.Fab")
			(hide yes)
			(effects
				(font
					(size 1.016 1.016)
					(thickness 0.1524)
				)
				(justify mirror)
			)
		)
		(duplicate_pad_numbers_are_jumpers no)
		(fp_rect
			(start 0.4318 0.9525)
			(end -0.4318 -0.9525)
			(stroke
				(width 0)
				(type default)
			)
			(fill no)
			(layer "B.CrtYd")
		)
		(fp_rect
			(start 0.4318 0.9525)
			(end -0.4318 -0.9525)
			(stroke
				(width 0)
				(type default)
			)
			(fill no)
			(layer "B.Fab")
		)
		(pad "1" smd custom
			(at 0 -0.4445 90)
			(size 0.1524 0.1524)
			(layers "B.Cu" "B.Mask" "B.Paste")
			(net "P1V26_STBY")
			(options
				(clearance outline)
				(anchor circle)
			)
			(primitives
				(gr_poly
					(pts
						(arc
							(start 0.3048 0.2032)
							(mid 0.275042 0.275042)
							(end 0.2032 0.3048)
						)
						(arc
							(start -0.2032 0.3048)
							(mid -0.275042 0.275042)
							(end -0.3048 0.2032)
						)
						(arc
							(start -0.3048 -0.2032)
							(mid -0.275042 -0.275042)
							(end -0.2032 -0.3048)
						)
						(arc
							(start 0.2032 -0.3048)
							(mid 0.275042 -0.275042)
							(end 0.3048 -0.2032)
						)
					)
					(width 0)
					(fill yes)
				)
			)
		)
		(pad "2" smd custom
			(at 0 0.4445 90)
			(size 0.1524 0.1524)
			(layers "B.Cu" "B.Mask" "B.Paste")
			(net "GND")
			(options
				(clearance outline)
				(anchor circle)
			)
			(primitives
				(gr_poly
					(pts
						(arc
							(start 0.3048 0.2032)
							(mid 0.275042 0.275042)
							(end 0.2032 0.3048)
						)
						(arc
							(start -0.2032 0.3048)
							(mid -0.275042 0.275042)
							(end -0.3048 0.2032)
						)
						(arc
							(start -0.3048 -0.2032)
							(mid -0.275042 -0.275042)
							(end -0.2032 -0.3048)
						)
						(arc
							(start 0.2032 -0.3048)
							(mid 0.275042 -0.275042)
							(end 0.3048 -0.2032)
						)
					)
					(width 0)
					(fill yes)
				)
			)
		)
	)
)
